(kicad_pcb
	(version 20260206)
	(generator "pcbnew")
	(generator_version "10.0")
	(general
		(thickness 1.6)
		(legacy_teardrops no)
	)
	(paper "A4")
	(title_block
		(title "04192023_DAF0TMB3IC0_F0TG_MB_C_brd_V02_OCP.brd")
		(comment 1 "Grand Teton / footprints 3756-3760 of 8354")
	)
	(layers
		(0 "F.Cu" signal "TOP")
		(4 "In1.Cu" signal "GND")
		(6 "In2.Cu" signal "IN1")
		(8 "In3.Cu" signal "GND1")
		(10 "In4.Cu" signal "IN2")
		(12 "In5.Cu" signal "GND2")
		(14 "In6.Cu" signal "IN3")
		(16 "In7.Cu" signal "GND3")
		(18 "In8.Cu" signal "VCC")
		(20 "In9.Cu" signal "VCC1")
		(22 "In10.Cu" signal "GND4")
		(24 "In11.Cu" signal "IN4")
		(26 "In12.Cu" signal "GND5")
		(28 "In13.Cu" signal "IN5")
		(30 "In14.Cu" signal "GND6")
		(32 "In15.Cu" signal "IN6")
		(34 "In16.Cu" signal "GND7")
		(2 "B.Cu" signal "BOTTOM")
		(9 "F.Adhes" user "F.Adhesive")
		(11 "B.Adhes" user "B.Adhesive")
		(13 "F.Paste" user "Package Geometry/Pastemask Top")
		(15 "B.Paste" user "Package Geometry/Pastemask Bottom")
		(5 "F.SilkS" user "Ref Des/Silkscreen Top")
		(7 "B.SilkS" user "Ref Des/Silkscreen Bottom")
		(1 "F.Mask" user "Board Geometry/Soldermask Top")
		(3 "B.Mask" user "Board Geometry/Soldermask Bottom")
		(17 "Dwgs.User" user "User.Drawings")
		(19 "Cmts.User" user "User.Comments")
		(21 "Eco1.User" user "User.Eco1")
		(23 "Eco2.User" user "User.Eco2")
		(25 "Edge.Cuts" user "Board Geometry/Outline")
		(27 "Margin" user)
		(31 "F.CrtYd" user "Package Geometry/Place Bound Top")
		(29 "B.CrtYd" user "Package Geometry/Place Bound Bottom")
		(35 "F.Fab" user "Ref Des/Assembly Top")
		(33 "B.Fab" user "Ref Des/Assembly Bottom")
	)
	(footprint ""
		(layer "F.Cu")
		(at 178.689 -406.527)
		(property "Reference" "PR2106"
			(at 0 0 0)
			(layer "F.SilkS")
			(hide yes)
			(effects
				(font
					(size 1.27 1.27)
				)
			)
		)
		(property "Value" ""
			(at 0 0 0)
			(layer "F.Fab")
			(effects
				(font
					(size 1.27 1.27)
				)
			)
		)
		(duplicate_pad_numbers_are_jumpers no)
		(fp_line
			(start -0.7874 -0.4064)
			(end 0.7874 -0.4064)
			(stroke
				(width 0.1524)
				(type default)
			)
			(layer "F.SilkS")
		)
		(fp_line
			(start -0.7874 0.4064)
			(end -0.7874 -0.4064)
			(stroke
				(width 0.1524)
				(type default)
			)
			(layer "F.SilkS")
		)
		(fp_line
			(start 0.7874 -0.4064)
			(end 0.7874 0.4064)
			(stroke
				(width 0.1524)
				(type default)
			)
			(layer "F.SilkS")
		)
		(fp_line
			(start 0.7874 0.4064)
			(end -0.7874 0.4064)
			(stroke
				(width 0.1524)
				(type default)
			)
			(layer "F.SilkS")
		)
		(fp_line
			(start -0.67945 -0.305054)
			(end -0.12065 -0.305054)
			(stroke
				(width 0.1)
				(type default)
			)
			(layer "F.Fab")
		)
		(fp_line
			(start -0.67945 0.3048)
			(end -0.67945 -0.305054)
			(stroke
				(width 0.1)
				(type default)
			)
			(layer "F.Fab")
		)
		(fp_line
			(start -0.12065 -0.305054)
			(end -0.12065 -0.2794)
			(stroke
				(width 0.1)
				(type default)
			)
			(layer "F.Fab")
		)
		(fp_line
			(start -0.12065 -0.2794)
			(end 0.12065 -0.2794)
			(stroke
				(width 0.1)
				(type default)
			)
			(layer "F.Fab")
		)
		(fp_line
			(start -0.12065 0.2794)
			(end -0.12065 0.3048)
			(stroke
				(width 0.1)
				(type default)
			)
			(layer "F.Fab")
		)
		(fp_line
			(start -0.12065 0.3048)
			(end -0.67945 0.3048)
			(stroke
				(width 0.1)
				(type default)
			)
			(layer "F.Fab")
		)
		(fp_line
			(start 0.120396 0.2794)
			(end -0.12065 0.2794)
			(stroke
				(width 0.1)
				(type default)
			)
			(layer "F.Fab")
		)
		(fp_line
			(start 0.120396 0.3048)
			(end 0.120396 0.2794)
			(stroke
				(width 0.1)
				(type default)
			)
			(layer "F.Fab")
		)
		(fp_line
			(start 0.12065 -0.3048)
			(end 0.67945 -0.3048)
			(stroke
				(width 0.1)
				(type default)
			)
			(layer "F.Fab")
		)
		(fp_line
			(start 0.12065 -0.2794)
			(end 0.12065 -0.3048)
			(stroke
				(width 0.1)
				(type default)
			)
			(layer "F.Fab")
		)
		(fp_line
			(start 0.67945 -0.3048)
			(end 0.67945 0.3048)
			(stroke
				(width 0.1)
				(type default)
			)
			(layer "F.Fab")
		)
		(fp_line
			(start 0.67945 0.3048)
			(end 0.120396 0.3048)
			(stroke
				(width 0.1)
				(type default)
			)
			(layer "F.Fab")
		)
		(pad "1" smd circle
			(at -0.40005 0)
			(size 0 0)
			(layers "F.Cu" "F.Mask" "F.Paste")
			(net "HSC_VDD")
		)
		(pad "2" smd circle
			(at 0.40005 0)
			(size 0 0)
			(layers "F.Cu" "F.Mask" "F.Paste")
			(net "HSC_VIN_UVW_N")
		)
	)
	(footprint ""
		(layer "F.Cu")
		(at 37.211 -363.093)
		(property "Reference" "PC367"
			(at 0 0 0)
			(layer "F.SilkS")
			(hide yes)
			(effects
				(font
					(size 1.27 1.27)
				)
			)
		)
		(property "Value" ""
			(at 0 0 0)
			(layer "F.Fab")
			(effects
				(font
					(size 1.27 1.27)
				)
			)
		)
		(duplicate_pad_numbers_are_jumpers no)
		(fp_line
			(start -0.7874 -0.4064)
			(end 0.7874 -0.4064)
			(stroke
				(width 0.1524)
				(type default)
			)
			(layer "F.SilkS")
		)
		(fp_line
			(start -0.7874 0.4064)
			(end -0.7874 -0.4064)
			(stroke
				(width 0.1524)
				(type default)
			)
			(layer "F.SilkS")
		)
		(fp_line
			(start 0.7874 -0.4064)
			(end 0.7874 0.4064)
			(stroke
				(width 0.1524)
				(type default)
			)
			(layer "F.SilkS")
		)
		(fp_line
			(start 0.7874 0.4064)
			(end -0.7874 0.4064)
			(stroke
				(width 0.1524)
				(type default)
			)
			(layer "F.SilkS")
		)
		(fp_line
			(start -0.67945 -0.305054)
			(end -0.12065 -0.305054)
			(stroke
				(width 0.1)
				(type default)
			)
			(layer "F.Fab")
		)
		(fp_line
			(start -0.67945 0.3048)
			(end -0.67945 -0.305054)
			(stroke
				(width 0.1)
				(type default)
			)
			(layer "F.Fab")
		)
		(fp_line
			(start -0.12065 -0.305054)
			(end -0.12065 -0.2794)
			(stroke
				(width 0.1)
				(type default)
			)
			(layer "F.Fab")
		)
		(fp_line
			(start -0.12065 -0.2794)
			(end 0.12065 -0.2794)
			(stroke
				(width 0.1)
				(type default)
			)
			(layer "F.Fab")
		)
		(fp_line
			(start -0.12065 0.2794)
			(end -0.12065 0.3048)
			(stroke
				(width 0.1)
				(type default)
			)
			(layer "F.Fab")
		)
		(fp_line
			(start -0.12065 0.3048)
			(end -0.67945 0.3048)
			(stroke
				(width 0.1)
				(type default)
			)
			(layer "F.Fab")
		)
		(fp_line
			(start 0.120396 0.2794)
			(end -0.12065 0.2794)
			(stroke
				(width 0.1)
				(type default)
			)
			(layer "F.Fab")
		)
		(fp_line
			(start 0.120396 0.3048)
			(end 0.120396 0.2794)
			(stroke
				(width 0.1)
				(type default)
			)
			(layer "F.Fab")
		)
		(fp_line
			(start 0.12065 -0.3048)
			(end 0.67945 -0.3048)
			(stroke
				(width 0.1)
				(type default)
			)
			(layer "F.Fab")
		)
		(fp_line
			(start 0.12065 -0.2794)
			(end 0.12065 -0.3048)
			(stroke
				(width 0.1)
				(type default)
			)
			(layer "F.Fab")
		)
		(fp_line
			(start 0.67945 -0.3048)
			(end 0.67945 0.3048)
			(stroke
				(width 0.1)
				(type default)
			)
			(layer "F.Fab")
		)
		(fp_line
			(start 0.67945 0.3048)
			(end 0.120396 0.3048)
			(stroke
				(width 0.1)
				(type default)
			)
			(layer "F.Fab")
		)
		(pad "1" smd circle
			(at -0.40005 0)
			(size 0 0)
			(layers "F.Cu" "F.Mask" "F.Paste")
			(net "PVDDIO_P1_TEMP1")
		)
		(pad "2" smd circle
			(at 0.40005 0)
			(size 0 0)
			(layers "F.Cu" "F.Mask" "F.Paste")
			(net "GND")
		)
	)
	(footprint ""
		(layer "F.Cu")
		(at 155.419552 -121.819924 180)
		(property "Reference" "U325"
			(at -0.155956 2.20472 0)
			(unlocked yes)
			(layer "F.SilkS")
			(effects
				(font
					(size 0.7874 0.5842)
					(thickness 0.1524)
				)
			)
		)
		(property "Value" ""
			(at 0 0 180)
			(layer "F.Fab")
			(effects
				(font
					(size 1.27 1.27)
				)
			)
		)
		(duplicate_pad_numbers_are_jumpers no)
		(fp_line
			(start 1.949958 1.610106)
			(end -1.949958 1.610106)
			(stroke
				(width 0.1524)
				(type default)
			)
			(layer "F.SilkS")
		)
		(fp_line
			(start 1.949958 -1.560068)
			(end 1.949958 1.610106)
			(stroke
				(width 0.1524)
				(type default)
			)
			(layer "F.SilkS")
		)
		(fp_line
			(start -1.949958 1.610106)
			(end -1.949958 -1.610106)
			(stroke
				(width 0.1524)
				(type default)
			)
			(layer "F.SilkS")
		)
		(fp_line
			(start -1.949958 -1.610106)
			(end 1.949958 -1.610106)
			(stroke
				(width 0.1524)
				(type default)
			)
			(layer "F.SilkS")
		)
		(fp_line
			(start 0.750062 1.560068)
			(end -0.750062 1.560068)
			(stroke
				(width 0.1)
				(type default)
			)
			(layer "F.Fab")
		)
		(fp_line
			(start 0.750062 -1.560068)
			(end 0.750062 1.560068)
			(stroke
				(width 0.1)
				(type default)
			)
			(layer "F.Fab")
		)
		(fp_line
			(start -0.750062 1.560068)
			(end -0.750062 -1.560068)
			(stroke
				(width 0.1)
				(type default)
			)
			(layer "F.Fab")
		)
		(fp_line
			(start -0.750062 -1.560068)
			(end 0.750062 -1.560068)
			(stroke
				(width 0.1)
				(type default)
			)
			(layer "F.Fab")
		)
		(pad "D" smd rect
			(at 1.100074 0 90)
			(size 1.016 1.4224)
			(layers "F.Cu" "F.Mask" "F.Paste")
			(net "IRQ_UV_DETECT_N")
		)
		(pad "G" smd rect
			(at -1.100074 -0.94996 90)
			(size 1.016 1.4224)
			(layers "F.Cu" "F.Mask" "F.Paste")
			(net "A_P12V_STBY_FPH_GATE")
		)
		(pad "S" smd rect
			(at -1.100074 0.94996 90)
			(size 1.016 1.4224)
			(layers "F.Cu" "F.Mask" "F.Paste")
			(net "GND")
		)
	)
	(footprint ""
		(layer "F.Cu")
		(at 329.592178 -46.748954 180)
		(property "Reference" "R1799"
			(at 0 0 180)
			(layer "F.SilkS")
			(hide yes)
			(effects
				(font
					(size 1.27 1.27)
				)
			)
		)
		(property "Value" ""
			(at 0 0 180)
			(layer "F.Fab")
			(effects
				(font
					(size 1.27 1.27)
				)
			)
		)
		(duplicate_pad_numbers_are_jumpers no)
		(fp_line
			(start 0.7874 0.4064)
			(end -0.7874 0.4064)
			(stroke
				(width 0.1524)
				(type default)
			)
			(layer "F.SilkS")
		)
		(fp_line
			(start 0.7874 -0.4064)
			(end 0.7874 0.4064)
			(stroke
				(width 0.1524)
				(type default)
			)
			(layer "F.SilkS")
		)
		(fp_line
			(start -0.7874 0.4064)
			(end -0.7874 -0.4064)
			(stroke
				(width 0.1524)
				(type default)
			)
			(layer "F.SilkS")
		)
		(fp_line
			(start -0.7874 -0.4064)
			(end 0.7874 -0.4064)
			(stroke
				(width 0.1524)
				(type default)
			)
			(layer "F.SilkS")
		)
		(fp_line
			(start 0.67945 0.3048)
			(end 0.120396 0.3048)
			(stroke
				(width 0.1)
				(type default)
			)
			(layer "F.Fab")
		)
		(fp_line
			(start 0.67945 -0.3048)
			(end 0.67945 0.3048)
			(stroke
				(width 0.1)
				(type default)
			)
			(layer "F.Fab")
		)
		(fp_line
			(start 0.12065 -0.2794)
			(end 0.12065 -0.3048)
			(stroke
				(width 0.1)
				(type default)
			)
			(layer "F.Fab")
		)
		(fp_line
			(start 0.12065 -0.3048)
			(end 0.67945 -0.3048)
			(stroke
				(width 0.1)
				(type default)
			)
			(layer "F.Fab")
		)
		(fp_line
			(start 0.120396 0.3048)
			(end 0.120396 0.2794)
			(stroke
				(width 0.1)
				(type default)
			)
			(layer "F.Fab")
		)
		(fp_line
			(start 0.120396 0.2794)
			(end -0.12065 0.2794)
			(stroke
				(width 0.1)
				(type default)
			)
			(layer "F.Fab")
		)
		(fp_line
			(start -0.12065 0.3048)
			(end -0.67945 0.3048)
			(stroke
				(width 0.1)
				(type default)
			)
			(layer "F.Fab")
		)
		(fp_line
			(start -0.12065 0.2794)
			(end -0.12065 0.3048)
			(stroke
				(width 0.1)
				(type default)
			)
			(layer "F.Fab")
		)
		(fp_line
			(start -0.12065 -0.2794)
			(end 0.12065 -0.2794)
			(stroke
				(width 0.1)
				(type default)
			)
			(layer "F.Fab")
		)
		(fp_line
			(start -0.12065 -0.305054)
			(end -0.12065 -0.2794)
			(stroke
				(width 0.1)
				(type default)
			)
			(layer "F.Fab")
		)
		(fp_line
			(start -0.67945 0.3048)
			(end -0.67945 -0.305054)
			(stroke
				(width 0.1)
				(type default)
			)
			(layer "F.Fab")
		)
		(fp_line
			(start -0.67945 -0.305054)
			(end -0.12065 -0.305054)
			(stroke
				(width 0.1)
				(type default)
			)
			(layer "F.Fab")
		)
		(pad "1" smd circle
			(at -0.40005 0 180)
			(size 0 0)
			(layers "F.Cu" "F.Mask" "F.Paste")
			(net "P12V_AUX")
		)
		(pad "2" smd circle
			(at 0.40005 0 180)
			(size 0 0)
			(layers "F.Cu" "F.Mask" "F.Paste")
			(net "P12V_AUX_ADC")
		)
	)
	(footprint ""
		(layer "F.Cu")
		(at 199.536558 -401.920202 180)
		(property "Reference" "PU287"
			(at 3.001772 -4.951222 90)
			(unlocked yes)
			(layer "F.SilkS")
			(effects
				(font
					(size 0.7874 0.5842)
					(thickness 0.1524)
				)
			)
		)
		(property "Value" ""
			(at 0 0 180)
			(layer "F.Fab")
			(effects
				(font
					(size 1.27 1.27)
				)
			)
		)
		(duplicate_pad_numbers_are_jumpers no)
		(fp_line
			(start 2.567686 2.567686)
			(end 2.567686 -2.567686)
			(stroke
				(width 0.1524)
				(type default)
			)
			(layer "F.SilkS")
		)
		(fp_line
			(start 2.567686 -2.567686)
			(end -2.567686 -2.567686)
			(stroke
				(width 0.1524)
				(type default)
			)
			(layer "F.SilkS")
		)
		(fp_line
			(start -2.567686 2.567686)
			(end 2.567686 2.567686)
			(stroke
				(width 0.1524)
				(type default)
			)
			(layer "F.SilkS")
		)
		(fp_line
			(start -2.567686 -2.567686)
			(end -2.567686 2.567686)
			(stroke
				(width 0.1524)
				(type default)
			)
			(layer "F.SilkS")
		)
		(fp_poly
			(pts
				(xy -2.632456 -2.13233) (xy -3.709924 -2.491486) (xy -2.991612 -3.209798)
			)
			(stroke
				(width 0)
				(type default)
			)
			(fill yes)
			(layer "F.SilkS")
		)
		(fp_line
			(start 2.549906 2.549906)
			(end 2.549906 -2.549906)
			(stroke
				(width 0.1)
				(type default)
			)
			(layer "F.Fab")
		)
		(fp_line
			(start 2.549906 -2.549906)
			(end -2.549906 -2.549906)
			(stroke
				(width 0.1)
				(type default)
			)
			(layer "F.Fab")
		)
		(fp_line
			(start -2.549906 2.549906)
			(end 2.549906 2.549906)
			(stroke
				(width 0.1)
				(type default)
			)
			(layer "F.Fab")
		)
		(fp_line
			(start -2.549906 -2.549906)
			(end -2.549906 2.549906)
			(stroke
				(width 0.1)
				(type default)
			)
			(layer "F.Fab")
		)
		(fp_poly
			(pts
				(xy -3.806698 -2.25806) (xy -3.806698 -1.24206) (xy -2.790698 -1.75006)
			)
			(stroke
				(width 0)
				(type default)
			)
			(fill yes)
			(layer "F.Fab")
		)
		(pad "1" smd rect
			(at -2.250186 -1.75006 270)
			(size 0.254 0.3556)
			(layers "F.Cu" "F.Mask" "F.Paste")
			(net "P12V_AUX")
		)
		(pad "2" smd rect
			(at -2.237486 -1.249934 270)
			(size 0.254 0.381)
			(layers "F.Cu" "F.Mask" "F.Paste")
			(net "P12V_AUX")
		)
		(pad "3" smd rect
			(at -2.237486 -0.750062 270)
			(size 0.254 0.381)
			(layers "F.Cu" "F.Mask" "F.Paste")
			(net "HSC_D_OC_1")
		)
		(pad "4" smd rect
			(at -2.237486 -0.249936 270)
			(size 0.254 0.381)
			(layers "F.Cu" "F.Mask" "F.Paste")
			(net "HSC_ON")
		)
		(pad "5" smd rect
			(at -2.237486 0.249936 270)
			(size 0.254 0.381)
			(layers "F.Cu" "F.Mask" "F.Paste")
			(net "HSC_FAULT")
		)
		(pad "6" smd rect
			(at -2.237486 0.750062 270)
			(size 0.254 0.381)
			(layers "F.Cu" "F.Mask" "F.Paste")
			(net "HSC_FLT_TYPE_1")
		)
		(pad "7" smd rect
			(at -2.237486 1.249934 270)
			(size 0.254 0.381)
			(layers "F.Cu" "F.Mask" "F.Paste")
			(net "HSC_NC1_1")
		)
		(pad "8" smd rect
			(at -2.250186 1.75006 270)
			(size 0.254 0.3556)
			(layers "F.Cu" "F.Mask" "F.Paste")
			(net "HSC_MODE_1")
		)
		(pad "9" smd rect
			(at -1.75006 2.250186 180)
			(size 0.254 0.3556)
			(layers "F.Cu" "F.Mask" "F.Paste")
			(net "P12V_PSU")
		)
		(pad "10" smd rect
			(at -1.249934 2.237486 180)
			(size 0.254 0.381)
			(layers "F.Cu" "F.Mask" "F.Paste")
			(net "P12V_PSU")
		)
		(pad "11" smd rect
			(at -0.750062 2.237486 180)
			(size 0.254 0.381)
			(layers "F.Cu" "F.Mask" "F.Paste")
			(net "P12V_PSU")
		)
		(pad "12" smd rect
			(at -0.249936 2.237486 180)
			(size 0.254 0.381)
			(layers "F.Cu" "F.Mask" "F.Paste")
			(net "P12V_PSU")
		)
		(pad "13" smd rect
			(at 0.249936 2.237486 180)
			(size 0.254 0.381)
			(layers "F.Cu" "F.Mask" "F.Paste")
			(net "P12V_PSU")
		)
		(pad "14" smd rect
			(at 0.750062 2.237486 180)
			(size 0.254 0.381)
			(layers "F.Cu" "F.Mask" "F.Paste")
			(net "P12V_PSU")
		)
		(pad "15" smd rect
			(at 1.249934 2.237486 180)
			(size 0.254 0.381)
			(layers "F.Cu" "F.Mask" "F.Paste")
			(net "P12V_PSU")
		)
		(pad "16" smd rect
			(at 1.75006 2.250186 180)
			(size 0.254 0.3556)
			(layers "F.Cu" "F.Mask" "F.Paste")
			(net "P12V_PSU")
		)
		(pad "17" smd rect
			(at 2.250186 1.75006 270)
			(size 0.254 0.3556)
			(layers "F.Cu" "F.Mask" "F.Paste")
			(net "HSC_SCREF_1")
		)
		(pad "18" smd rect
			(at 2.237486 1.249934 270)
			(size 0.254 0.381)
			(layers "F.Cu" "F.Mask" "F.Paste")
			(net "HSC_VTEMP")
		)
		(pad "19" smd rect
			(at 2.237486 0.750062 270)
			(size 0.254 0.381)
			(layers "F.Cu" "F.Mask" "F.Paste")
			(net "HSC_SS")
		)
		(pad "20" smd rect
			(at 2.237486 0.249936 270)
			(size 0.254 0.381)
			(layers "F.Cu" "F.Mask" "F.Paste")
			(net "AGND_HSC")
		)
		(pad "21" smd rect
			(at 2.237486 -0.249936 270)
			(size 0.254 0.381)
			(layers "F.Cu" "F.Mask" "F.Paste")
			(net "HSC_VDD_R_1")
		)
		(pad "22" smd rect
			(at 2.237486 -0.750062 270)
			(size 0.254 0.381)
			(layers "F.Cu" "F.Mask" "F.Paste")
			(net "HSC_IMON")
		)
		(pad "23" smd rect
			(at 2.237486 -1.249934 270)
			(size 0.254 0.381)
			(layers "F.Cu" "F.Mask" "F.Paste")
			(net "HSC_CS_1")
		)
		(pad "24" smd rect
			(at 2.250186 -1.75006 270)
			(size 0.254 0.3556)
			(layers "F.Cu" "F.Mask" "F.Paste")
			(net "HSC_OCREF")
		)
		(pad "25" smd rect
			(at 1.75006 -2.250186 180)
			(size 0.254 0.3556)
			(layers "F.Cu" "F.Mask" "F.Paste")
			(net "P12V_AUX")
		)
		(pad "26" smd rect
			(at 1.249934 -2.237486 180)
			(size 0.254 0.381)
			(layers "F.Cu" "F.Mask" "F.Paste")
			(net "P12V_AUX")
		)
		(pad "27" smd rect
			(at 0.750062 -2.237486 180)
			(size 0.254 0.381)
			(layers "F.Cu" "F.Mask" "F.Paste")
			(net "P12V_AUX")
		)
		(pad "28" smd rect
			(at 0.249936 -2.237486 180)
			(size 0.254 0.381)
			(layers "F.Cu" "F.Mask" "F.Paste")
			(net "P12V_AUX")
		)
		(pad "29" smd rect
			(at -0.249936 -2.237486 180)
			(size 0.254 0.381)
			(layers "F.Cu" "F.Mask" "F.Paste")
			(net "P12V_AUX")
		)
		(pad "30" smd rect
			(at -0.750062 -2.237486 180)
			(size 0.254 0.381)
			(layers "F.Cu" "F.Mask" "F.Paste")
			(net "P12V_AUX")
		)
		(pad "31" smd rect
			(at -1.249934 -2.237486 180)
			(size 0.254 0.381)
			(layers "F.Cu" "F.Mask" "F.Paste")
			(net "P12V_AUX")
		)
		(pad "32" smd rect
			(at -1.75006 -2.250186 180)
			(size 0.254 0.3556)
			(layers "F.Cu" "F.Mask" "F.Paste")
			(net "P12V_AUX")
		)
		(pad "33" smd rect
			(at 0 0 180)
			(size 3.4036 3.4036)
			(layers "F.Cu" "F.Mask" "F.Paste")
			(net "P12V_PSU")
		)
		(zone
			(layer "F.Cu")
			(hatch none 0.5)
			(connect_pads
				(clearance 0)
			)
			(min_thickness 0.25)
			(keepout
				(tracks not_allowed)
				(vias allowed)
				(pads allowed)
				(copperpour not_allowed)
				(footprints allowed)
			)
			(placement
				(enabled no)
				(sheetname "")
			)
			(fill
				(thermal_gap 0.5)
				(thermal_bridge_width 0.5)
				(island_removal_mode 0)
			)
			(polygon
				(pts
					(xy 197.514972 -403.61108) (xy 197.783958 -403.61108) (xy 197.783958 -400.167602) (xy 201.289158 -400.167602)
					(xy 201.289158 -402.428202) (xy 201.532744 -402.428202) (xy 201.532744 -400.472402) (xy 201.558144 -400.472402)
					(xy 201.558144 -399.898616) (xy 200.984358 -399.898616) (xy 200.984358 -399.924016) (xy 198.088758 -399.924016)
					(xy 198.088758 -399.898616) (xy 197.514972 -399.898616) (xy 197.514972 -400.472402) (xy 197.540372 -400.472402)
					(xy 197.540372 -403.368002) (xy 197.514972 -403.368002)
				)
			)
		)
	)
)
